(kicad_pcb
	(version 20260206)
	(generator "pcbnew")
	(generator_version "10.0")
	(general
		(thickness 1.6)
		(legacy_teardrops no)
	)
	(paper "A4")
	(title_block
		(title "Bryce Canyon_IOM_M2_16342-2_OCP.brd")
		(comment 1 "Bryce Canyon / footprints 124-130 of 1146")
	)
	(layers
		(0 "F.Cu" signal "TOP")
		(4 "In1.Cu" signal "L2GND")
		(6 "In2.Cu" signal "L3")
		(8 "In3.Cu" signal "L4VCC")
		(10 "In4.Cu" signal "L5VCC")
		(12 "In5.Cu" signal "L6")
		(14 "In6.Cu" signal "L7GND")
		(2 "B.Cu" signal "BOTTOM")
		(9 "F.Adhes" user "F.Adhesive")
		(11 "B.Adhes" user "B.Adhesive")
		(13 "F.Paste" user "Package Geometry/Pastemask Top")
		(15 "B.Paste" user "Package Geometry/Pastemask Bottom")
		(5 "F.SilkS" user "Ref Des/Silkscreen Top")
		(7 "B.SilkS" user "Ref Des/Silkscreen Bottom")
		(1 "F.Mask" user "Board Geometry/Soldermask Top")
		(3 "B.Mask" user "Board Geometry/Soldermask Bottom")
		(17 "Dwgs.User" user "User.Drawings")
		(19 "Cmts.User" user "User.Comments")
		(21 "Eco1.User" user "User.Eco1")
		(23 "Eco2.User" user "User.Eco2")
		(25 "Edge.Cuts" user "Board Geometry/Outline")
		(27 "Margin" user)
		(31 "F.CrtYd" user "Package Geometry/Place Bound Top")
		(29 "B.CrtYd" user "Package Geometry/Place Bound Bottom")
		(35 "F.Fab" user "Ref Des/Assembly Top")
		(33 "B.Fab" user "Ref Des/Assembly Bottom")
	)
	(footprint ""
		(layer "F.Cu")
		(at 91.059 -29.464 -90)
		(property "Reference" "U98"
			(at 0 0 270)
			(layer "F.SilkS")
			(hide yes)
			(effects
				(font
					(size 1.27 1.27)
				)
			)
		)
		(property "Value" "TPS2065DBVT-GP"
			(at 0 -5.1308 270)
			(unlocked yes)
			(layer "F.Fab")
			(hide yes)
			(effects
				(font
					(size 1.016 1.016)
					(thickness 0.1524)
				)
			)
		)
		(property "Device Type" "SOT-23-5H58"
			(at 0 -6.7564 270)
			(unlocked yes)
			(layer "F.Fab")
			(hide yes)
			(effects
				(font
					(size 1.016 1.016)
					(thickness 0.1524)
				)
			)
		)
		(duplicate_pad_numbers_are_jumpers no)
		(fp_line
			(start -1.778 2.286)
			(end -0.254 2.286)
			(stroke
				(width 0.1524)
				(type default)
			)
			(layer "F.SilkS")
		)
		(fp_line
			(start -1.778 2.286)
			(end 1.778 2.286)
			(stroke
				(width 0.1524)
				(type default)
			)
			(layer "F.SilkS")
		)
		(fp_line
			(start -0.254 2.286)
			(end 1.778 2.286)
			(stroke
				(width 0.1524)
				(type default)
			)
			(layer "F.SilkS")
		)
		(fp_line
			(start 1.778 2.286)
			(end 1.778 -2.286)
			(stroke
				(width 0.1524)
				(type default)
			)
			(layer "F.SilkS")
		)
		(fp_line
			(start -1.7272 2.2352)
			(end -1.7272 0.762)
			(stroke
				(width 0.3302)
				(type default)
			)
			(layer "F.SilkS")
		)
		(fp_line
			(start -0.7112 2.2352)
			(end -1.7272 2.2352)
			(stroke
				(width 0.3302)
				(type default)
			)
			(layer "F.SilkS")
		)
		(fp_line
			(start -1.778 -2.286)
			(end -1.778 2.286)
			(stroke
				(width 0.1524)
				(type default)
			)
			(layer "F.SilkS")
		)
		(fp_line
			(start 1.778 -2.286)
			(end -1.778 -2.286)
			(stroke
				(width 0.1524)
				(type default)
			)
			(layer "F.SilkS")
		)
		(fp_poly
			(pts
				(xy -2.03708 1.279144) (xy -2.39268 0.923544) (xy -2.39268 1.634744)
			)
			(stroke
				(width 0)
				(type default)
			)
			(fill yes)
			(layer "F.SilkS")
		)
		(fp_rect
			(start -1.778 2.286)
			(end 1.778 -2.286)
			(stroke
				(width 0)
				(type default)
			)
			(fill no)
			(layer "F.CrtYd")
		)
		(fp_rect
			(start -1.778 2.286)
			(end 1.778 -2.286)
			(stroke
				(width 0)
				(type default)
			)
			(fill no)
			(layer "F.Fab")
		)
		(pad "1" smd rect
			(at -0.94996 1.143 270)
			(size 0.508 1.524)
			(layers "F.Cu" "F.Mask" "F.Paste")
			(net "P5V_USB")
		)
		(pad "2" smd rect
			(at 0 1.143 270)
			(size 0.508 1.524)
			(layers "F.Cu" "F.Mask" "F.Paste")
			(net "GND")
		)
		(pad "3" smd rect
			(at 0.94996 1.143 270)
			(size 0.508 1.524)
			(layers "F.Cu" "F.Mask" "F.Paste")
			(net "USB_OCS_N1")
		)
		(pad "4" smd rect
			(at 0.94996 -1.143 270)
			(size 0.508 1.524)
			(layers "F.Cu" "F.Mask" "F.Paste")
			(net "USB_EN_1")
		)
		(pad "5" smd rect
			(at -0.94996 -1.143 270)
			(size 0.508 1.524)
			(layers "F.Cu" "F.Mask" "F.Paste")
			(net "P5V_STBY")
		)
	)
	(footprint ""
		(layer "F.Cu")
		(at 216.08542 -90.367612 180)
		(property "Reference" "R831"
			(at 0 0 180)
			(layer "F.SilkS")
			(hide yes)
			(effects
				(font
					(size 1.27 1.27)
				)
			)
		)
		(property "Value" "20KR2F-L-GP"
			(at 0.064008 -3.993896 180)
			(unlocked yes)
			(layer "F.Fab")
			(hide yes)
			(effects
				(font
					(size 1.016 1.016)
					(thickness 0.1524)
				)
			)
		)
		(property "Device Type" "R402H16"
			(at 0.064008 -5.517896 180)
			(unlocked yes)
			(layer "F.Fab")
			(hide yes)
			(effects
				(font
					(size 1.016 1.016)
					(thickness 0.1524)
				)
			)
		)
		(duplicate_pad_numbers_are_jumpers no)
		(fp_line
			(start 0.508 -0.9398)
			(end -0.508 -0.9398)
			(stroke
				(width 0.1524)
				(type default)
			)
			(layer "F.SilkS")
		)
		(fp_line
			(start -0.508 -0.9398)
			(end -0.508 0.9398)
			(stroke
				(width 0.1524)
				(type default)
			)
			(layer "F.SilkS")
		)
		(fp_rect
			(start -0.508 0.9398)
			(end 0.508 -0.9398)
			(stroke
				(width 0)
				(type default)
			)
			(fill no)
			(layer "F.CrtYd")
		)
		(fp_rect
			(start -0.508 0.9398)
			(end 0.508 -0.9398)
			(stroke
				(width 0)
				(type default)
			)
			(fill no)
			(layer "F.Fab")
		)
		(pad "1" smd custom
			(at 0 -0.4445 180)
			(size 0.1397 0.1397)
			(layers "F.Cu" "F.Mask" "F.Paste")
			(net "GND")
			(options
				(clearance outline)
				(anchor circle)
			)
			(primitives
				(gr_poly
					(pts
						(arc
							(start -0.1778 -0.2794)
							(mid -0.249642 -0.249642)
							(end -0.2794 -0.1778)
						)
						(arc
							(start -0.2794 0.1778)
							(mid -0.249642 0.249642)
							(end -0.1778 0.2794)
						)
						(arc
							(start 0.1778 0.2794)
							(mid 0.249642 0.249642)
							(end 0.2794 0.1778)
						)
						(arc
							(start 0.2794 -0.1778)
							(mid 0.249642 -0.249642)
							(end 0.1778 -0.2794)
						)
					)
					(width 0)
					(fill yes)
				)
			)
		)
		(pad "2" smd custom
			(at 0 0.4445 180)
			(size 0.1397 0.1397)
			(layers "F.Cu" "F.Mask" "F.Paste")
			(net "IOM_FULL_PGOOD")
			(options
				(clearance outline)
				(anchor circle)
			)
			(primitives
				(gr_poly
					(pts
						(arc
							(start -0.1778 -0.2794)
							(mid -0.249642 -0.249642)
							(end -0.2794 -0.1778)
						)
						(arc
							(start -0.2794 0.1778)
							(mid -0.249642 0.249642)
							(end -0.1778 0.2794)
						)
						(arc
							(start 0.1778 0.2794)
							(mid 0.249642 0.249642)
							(end 0.2794 0.1778)
						)
						(arc
							(start 0.2794 -0.1778)
							(mid 0.249642 -0.249642)
							(end 0.1778 -0.2794)
						)
					)
					(width 0)
					(fill yes)
				)
			)
		)
	)
	(footprint ""
		(layer "F.Cu")
		(at 35.2044 -134.5438 90)
		(property "Reference" "R280"
			(at 0 0 90)
			(layer "F.SilkS")
			(hide yes)
			(effects
				(font
					(size 1.27 1.27)
				)
			)
		)
		(property "Value" "33R2F-3-GP"
			(at 0.064008 -3.993896 90)
			(unlocked yes)
			(layer "F.Fab")
			(hide yes)
			(effects
				(font
					(size 1.016 1.016)
					(thickness 0.1524)
				)
			)
		)
		(property "Device Type" "R402H16"
			(at 0.064008 -5.517896 90)
			(unlocked yes)
			(layer "F.Fab")
			(hide yes)
			(effects
				(font
					(size 1.016 1.016)
					(thickness 0.1524)
				)
			)
		)
		(duplicate_pad_numbers_are_jumpers no)
		(fp_line
			(start 0.508 -0.9398)
			(end -0.508 -0.9398)
			(stroke
				(width 0.1524)
				(type default)
			)
			(layer "F.SilkS")
		)
		(fp_line
			(start -0.508 -0.9398)
			(end -0.508 0.9398)
			(stroke
				(width 0.1524)
				(type default)
			)
			(layer "F.SilkS")
		)
		(fp_rect
			(start -0.508 0.9398)
			(end 0.508 -0.9398)
			(stroke
				(width 0)
				(type default)
			)
			(fill no)
			(layer "F.CrtYd")
		)
		(fp_rect
			(start -0.508 0.9398)
			(end 0.508 -0.9398)
			(stroke
				(width 0)
				(type default)
			)
			(fill no)
			(layer "F.Fab")
		)
		(pad "1" smd custom
			(at 0 -0.4445 90)
			(size 0.1397 0.1397)
			(layers "F.Cu" "F.Mask" "F.Paste")
			(net "FLA_CS_0_R")
			(options
				(clearance outline)
				(anchor circle)
			)
			(primitives
				(gr_poly
					(pts
						(arc
							(start -0.1778 -0.2794)
							(mid -0.249642 -0.249642)
							(end -0.2794 -0.1778)
						)
						(arc
							(start -0.2794 0.1778)
							(mid -0.249642 0.249642)
							(end -0.1778 0.2794)
						)
						(arc
							(start 0.1778 0.2794)
							(mid 0.249642 0.249642)
							(end 0.2794 0.1778)
						)
						(arc
							(start 0.2794 -0.1778)
							(mid 0.249642 -0.249642)
							(end 0.1778 -0.2794)
						)
					)
					(width 0)
					(fill yes)
				)
			)
		)
		(pad "2" smd custom
			(at 0 0.4445 90)
			(size 0.1397 0.1397)
			(layers "F.Cu" "F.Mask" "F.Paste")
			(net "FLA_CS_0")
			(options
				(clearance outline)
				(anchor circle)
			)
			(primitives
				(gr_poly
					(pts
						(arc
							(start -0.1778 -0.2794)
							(mid -0.249642 -0.249642)
							(end -0.2794 -0.1778)
						)
						(arc
							(start -0.2794 0.1778)
							(mid -0.249642 0.249642)
							(end -0.1778 0.2794)
						)
						(arc
							(start 0.1778 0.2794)
							(mid 0.249642 0.249642)
							(end 0.2794 0.1778)
						)
						(arc
							(start 0.2794 -0.1778)
							(mid 0.249642 -0.249642)
							(end 0.1778 -0.2794)
						)
					)
					(width 0)
					(fill yes)
				)
			)
		)
	)
	(footprint ""
		(layer "F.Cu")
		(at 88.674194 -53.331872)
		(property "Reference" "PQ3"
			(at 0 0 0)
			(layer "F.SilkS")
			(hide yes)
			(effects
				(font
					(size 1.27 1.27)
				)
			)
		)
		(property "Value" "FDS8878-G-GP"
			(at -3.707384 -1.5367 0)
			(unlocked yes)
			(layer "F.Fab")
			(hide yes)
			(effects
				(font
					(size 1.016 1.016)
					(thickness 0.1524)
				)
			)
		)
		(property "Device Type" "SOIC8H69"
			(at -3.707384 -3.0607 0)
			(unlocked yes)
			(layer "F.Fab")
			(hide yes)
			(effects
				(font
					(size 1.016 1.016)
					(thickness 0.1524)
				)
			)
		)
		(duplicate_pad_numbers_are_jumpers no)
		(fp_line
			(start -2.7432 -1.4224)
			(end -2.7432 1.4224)
			(stroke
				(width 0.1524)
				(type default)
			)
			(layer "F.SilkS")
		)
		(fp_line
			(start -2.7432 1.4224)
			(end -2.6416 1.4224)
			(stroke
				(width 0.1524)
				(type default)
			)
			(layer "F.SilkS")
		)
		(fp_line
			(start -2.7432 1.4224)
			(end 2.1336 1.4224)
			(stroke
				(width 0.1524)
				(type default)
			)
			(layer "F.SilkS")
		)
		(fp_line
			(start -2.7178 -0.508)
			(end -2.1844 -0.0508)
			(stroke
				(width 0.1524)
				(type default)
			)
			(layer "F.SilkS")
		)
		(fp_line
			(start -2.6289 3.4417)
			(end -2.6289 1.4732)
			(stroke
				(width 0.381)
				(type default)
			)
			(layer "F.SilkS")
		)
		(fp_line
			(start -2.1844 -0.0508)
			(end -2.7178 0.508)
			(stroke
				(width 0.1524)
				(type default)
			)
			(layer "F.SilkS")
		)
		(fp_line
			(start 2.1336 -1.4224)
			(end -2.7432 -1.4224)
			(stroke
				(width 0.1524)
				(type default)
			)
			(layer "F.SilkS")
		)
		(fp_line
			(start 2.1336 1.4224)
			(end 2.1336 -1.4224)
			(stroke
				(width 0.1524)
				(type default)
			)
			(layer "F.SilkS")
		)
		(fp_poly
			(pts
				(xy -2.2098 -1.4224) (xy -2.2098 1.4224) (xy 2.2098 1.4224) (xy 2.2098 -1.4224)
			)
			(stroke
				(width 0)
				(type default)
			)
			(fill yes)
			(layer "F.SilkS")
		)
		(fp_rect
			(start -2.450084 2.999994)
			(end 2.450084 -2.999994)
			(stroke
				(width 0)
				(type default)
			)
			(fill no)
			(layer "F.CrtYd")
		)
		(fp_poly
			(pts
				(xy -2.8194 3.6322) (xy -2.8194 -3.6322) (xy 2.8194 -3.6322) (xy 2.8194 1.18364) (xy 2.450084 1.18364)
				(xy 2.450084 -2.999994) (xy -2.450084 -2.999994) (xy -2.450084 2.999994) (xy 2.450084 2.999994)
				(xy 2.450084 1.18618) (xy 2.8194 1.18618) (xy 2.8194 3.6322)
			)
			(stroke
				(width 0)
				(type default)
			)
			(fill no)
			(layer "F.CrtYd")
		)
		(fp_rect
			(start -2.8194 3.6322)
			(end 2.8194 -3.6322)
			(stroke
				(width 0)
				(type default)
			)
			(fill no)
			(layer "F.Fab")
		)
		(pad "1" smd rect
			(at -1.905 2.54)
			(size 0.635 1.651)
			(layers "F.Cu" "F.Mask" "F.Paste")
			(net "P3V3")
		)
		(pad "2" smd rect
			(at -0.635 2.54)
			(size 0.635 1.651)
			(layers "F.Cu" "F.Mask" "F.Paste")
			(net "P3V3")
		)
		(pad "3" smd rect
			(at 0.635 2.54)
			(size 0.635 1.651)
			(layers "F.Cu" "F.Mask" "F.Paste")
			(net "P3V3")
		)
		(pad "4" smd rect
			(at 1.905 2.54)
			(size 0.635 1.651)
			(layers "F.Cu" "F.Mask" "F.Paste")
			(net "PQ2_D")
		)
		(pad "5" smd rect
			(at 1.905 -2.54)
			(size 0.635 1.651)
			(layers "F.Cu" "F.Mask" "F.Paste")
			(net "P3V3_STBY")
		)
		(pad "6" smd rect
			(at 0.635 -2.54)
			(size 0.635 1.651)
			(layers "F.Cu" "F.Mask" "F.Paste")
			(net "P3V3_STBY")
		)
		(pad "7" smd rect
			(at -0.635 -2.54)
			(size 0.635 1.651)
			(layers "F.Cu" "F.Mask" "F.Paste")
			(net "P3V3_STBY")
		)
		(pad "8" smd rect
			(at -1.905 -2.54)
			(size 0.635 1.651)
			(layers "F.Cu" "F.Mask" "F.Paste")
			(net "P3V3_STBY")
		)
	)
	(footprint ""
		(layer "F.Cu")
		(at 10.796524 -138.144504 90)
		(property "Reference" "R230"
			(at 0 0 90)
			(layer "F.SilkS")
			(hide yes)
			(effects
				(font
					(size 1.27 1.27)
				)
			)
		)
		(property "Value" "120R2F-GP"
			(at 0.064008 -3.993896 90)
			(unlocked yes)
			(layer "F.Fab")
			(hide yes)
			(effects
				(font
					(size 1.016 1.016)
					(thickness 0.1524)
				)
			)
		)
		(property "Device Type" "R402H16"
			(at 0.064008 -5.517896 90)
			(unlocked yes)
			(layer "F.Fab")
			(hide yes)
			(effects
				(font
					(size 1.016 1.016)
					(thickness 0.1524)
				)
			)
		)
		(duplicate_pad_numbers_are_jumpers no)
		(fp_line
			(start 0.508 -0.9398)
			(end -0.508 -0.9398)
			(stroke
				(width 0.1524)
				(type default)
			)
			(layer "F.SilkS")
		)
		(fp_line
			(start -0.508 -0.9398)
			(end -0.508 0.9398)
			(stroke
				(width 0.1524)
				(type default)
			)
			(layer "F.SilkS")
		)
		(fp_rect
			(start -0.508 0.9398)
			(end 0.508 -0.9398)
			(stroke
				(width 0)
				(type default)
			)
			(fill no)
			(layer "F.CrtYd")
		)
		(fp_rect
			(start -0.508 0.9398)
			(end 0.508 -0.9398)
			(stroke
				(width 0)
				(type default)
			)
			(fill no)
			(layer "F.Fab")
		)
		(pad "1" smd custom
			(at 0 -0.4445 90)
			(size 0.1397 0.1397)
			(layers "F.Cu" "F.Mask" "F.Paste")
			(net "MEMBA_0")
			(options
				(clearance outline)
				(anchor circle)
			)
			(primitives
				(gr_poly
					(pts
						(arc
							(start -0.1778 -0.2794)
							(mid -0.249642 -0.249642)
							(end -0.2794 -0.1778)
						)
						(arc
							(start -0.2794 0.1778)
							(mid -0.249642 0.249642)
							(end -0.1778 0.2794)
						)
						(arc
							(start 0.1778 0.2794)
							(mid 0.249642 0.249642)
							(end 0.2794 0.1778)
						)
						(arc
							(start 0.2794 -0.1778)
							(mid 0.249642 -0.249642)
							(end 0.1778 -0.2794)
						)
					)
					(width 0)
					(fill yes)
				)
			)
		)
		(pad "2" smd custom
			(at 0 0.4445 90)
			(size 0.1397 0.1397)
			(layers "F.Cu" "F.Mask" "F.Paste")
			(net "P1V2_STBY")
			(options
				(clearance outline)
				(anchor circle)
			)
			(primitives
				(gr_poly
					(pts
						(arc
							(start -0.1778 -0.2794)
							(mid -0.249642 -0.249642)
							(end -0.2794 -0.1778)
						)
						(arc
							(start -0.2794 0.1778)
							(mid -0.249642 0.249642)
							(end -0.1778 0.2794)
						)
						(arc
							(start 0.1778 0.2794)
							(mid 0.249642 0.249642)
							(end 0.2794 0.1778)
						)
						(arc
							(start 0.2794 -0.1778)
							(mid 0.249642 -0.249642)
							(end 0.1778 -0.2794)
						)
					)
					(width 0)
					(fill yes)
				)
			)
		)
	)
	(footprint ""
		(layer "F.Cu")
		(at 33.9344 -162.941)
		(property "Reference" "L5"
			(at 0 0 0)
			(layer "F.SilkS")
			(hide yes)
			(effects
				(font
					(size 1.27 1.27)
				)
			)
		)
		(property "Value" "MMZ2012S601ATA1N-GP"
			(at 0 -4.2418 0)
			(unlocked yes)
			(layer "F.Fab")
			(hide yes)
			(effects
				(font
					(size 1.016 1.016)
					(thickness 0.1524)
				)
			)
		)
		(property "Device Type" "L805H42"
			(at 0 -5.7912 0)
			(unlocked yes)
			(layer "F.Fab")
			(hide yes)
			(effects
				(font
					(size 1.016 1.016)
					(thickness 0.1524)
				)
			)
		)
		(duplicate_pad_numbers_are_jumpers no)
		(fp_line
			(start -0.889 -1.7018)
			(end 0.889 -1.7018)
			(stroke
				(width 0.1524)
				(type default)
			)
			(layer "F.SilkS")
		)
		(fp_line
			(start -0.889 1.7018)
			(end -0.889 -1.7018)
			(stroke
				(width 0.1524)
				(type default)
			)
			(layer "F.SilkS")
		)
		(fp_line
			(start 0.889 -1.7018)
			(end 0.889 1.7018)
			(stroke
				(width 0.1524)
				(type default)
			)
			(layer "F.SilkS")
		)
		(fp_line
			(start 0.889 1.7018)
			(end -0.889 1.7018)
			(stroke
				(width 0.1524)
				(type default)
			)
			(layer "F.SilkS")
		)
		(fp_rect
			(start -0.9652 1.778)
			(end 0.9652 -1.778)
			(stroke
				(width 0)
				(type default)
			)
			(fill no)
			(layer "F.CrtYd")
		)
		(fp_rect
			(start -0.9652 1.778)
			(end 0.9652 -1.778)
			(stroke
				(width 0)
				(type default)
			)
			(fill no)
			(layer "F.Fab")
		)
		(pad "1" smd rect
			(at 0 -0.9652)
			(size 1.397 1.143)
			(layers "F.Cu" "F.Mask" "F.Paste")
			(net "P1V15_STBY")
		)
		(pad "2" smd rect
			(at 0 0.9652)
			(size 1.397 1.143)
			(layers "F.Cu" "F.Mask" "F.Paste")
			(net "V1PLLAV11")
		)
	)
	(footprint ""
		(layer "F.Cu")
		(at 183.9468 -101.18852)
		(property "Reference" "TP215"
			(at 0 0 0)
			(layer "F.SilkS")
			(hide yes)
			(effects
				(font
					(size 1.27 1.27)
				)
			)
		)
		(property "Value" "TPAD32-GP"
			(at -0.0508 -1.6764 0)
			(unlocked yes)
			(layer "F.Fab")
			(hide yes)
			(effects
				(font
					(size 1.016 1.016)
					(thickness 0.1524)
				)
			)
		)
		(property "Device Type" "TPAD32"
			(at -0.0508 -3.2004 0)
			(unlocked yes)
			(layer "F.Fab")
			(hide yes)
			(effects
				(font
					(size 1.016 1.016)
					(thickness 0.1524)
				)
			)
		)
		(duplicate_pad_numbers_are_jumpers no)
		(fp_poly
			(pts
				(arc
					(start 0.4064 0)
					(mid -0.4064 0)
					(end 0.4064 0)
				)
			)
			(stroke
				(width 0)
				(type default)
			)
			(fill no)
			(layer "F.CrtYd")
		)
		(fp_poly
			(pts
				(arc
					(start 0.7112 0)
					(mid -0.7112 0)
					(end 0.7112 0)
				)
			)
			(stroke
				(width 0)
				(type default)
			)
			(fill no)
			(layer "F.Fab")
		)
		(pad "1" smd circle
			(at 0 0)
			(size 0.8128 0.8128)
			(layers "F.Cu" "F.Mask" "F.Paste")
			(net "TEMP_1_ALERT")
		)
	)
)
